(kicad_pcb
	(version 20260206)
	(generator "pcbnew")
	(generator_version "10.0")
	(general
		(thickness 1.6)
		(legacy_teardrops no)
	)
	(paper "A4")
	(title_block
		(title "01162023_DA0F0TEBIF0_F0T_Expander_BD_F_brd_V02_OCP.brd")
		(comment 1 "Grand Teton / footprints 6652-6656 of 9728")
	)
	(layers
		(0 "F.Cu" signal "TOP")
		(4 "In1.Cu" signal "GND")
		(6 "In2.Cu" signal "VCC")
		(8 "In3.Cu" signal "VCC1")
		(10 "In4.Cu" signal "GND1")
		(12 "In5.Cu" signal "IN1")
		(14 "In6.Cu" signal "GND2")
		(16 "In7.Cu" signal "IN2")
		(18 "In8.Cu" signal "GND3")
		(20 "In9.Cu" signal "IN3")
		(22 "In10.Cu" signal "GND4")
		(24 "In11.Cu" signal "IN4")
		(26 "In12.Cu" signal "GND5")
		(28 "In13.Cu" signal "IN5")
		(30 "In14.Cu" signal "GND6")
		(32 "In15.Cu" signal "IN6")
		(34 "In16.Cu" signal "GND7")
		(2 "B.Cu" signal "BOTTOM")
		(9 "F.Adhes" user "F.Adhesive")
		(11 "B.Adhes" user "B.Adhesive")
		(13 "F.Paste" user "Package Geometry/Pastemask Top")
		(15 "B.Paste" user "Package Geometry/Pastemask Bottom")
		(5 "F.SilkS" user "Ref Des/Silkscreen Top")
		(7 "B.SilkS" user "Ref Des/Silkscreen Bottom")
		(1 "F.Mask" user "Board Geometry/Soldermask Top")
		(3 "B.Mask" user "Board Geometry/Soldermask Bottom")
		(17 "Dwgs.User" user "User.Drawings")
		(19 "Cmts.User" user "User.Comments")
		(21 "Eco1.User" user "User.Eco1")
		(23 "Eco2.User" user "User.Eco2")
		(25 "Edge.Cuts" user "Board Geometry/Outline")
		(27 "Margin" user)
		(31 "F.CrtYd" user "Package Geometry/Place Bound Top")
		(29 "B.CrtYd" user "Package Geometry/Place Bound Bottom")
		(35 "F.Fab" user "Ref Des/Assembly Top")
		(33 "B.Fab" user "Ref Des/Assembly Bottom")
	)
	(footprint ""
		(layer "F.Cu")
		(at 29.649674 -270.89989)
		(property "Reference" "H94"
			(at 4.294632 7.569962 0)
			(unlocked yes)
			(layer "F.SilkS")
			(effects
				(font
					(size 0.7874 0.5842)
					(thickness 0.1524)
				)
				(justify left)
			)
		)
		(property "Value" ""
			(at 0 0 0)
			(layer "F.Fab")
			(effects
				(font
					(size 1.27 1.27)
				)
			)
		)
		(duplicate_pad_numbers_are_jumpers no)
		(fp_arc
			(start 7.975854 -0.620014)
			(mid 7.993928 -0.310241)
			(end 7.999984 0)
			(stroke
				(width 0.1524)
				(type default)
			)
			(layer "F.SilkS")
		)
		(fp_arc
			(start 7.999984 0)
			(mid -7.46541 2.875054)
			(end 5.932932 -5.366766)
			(stroke
				(width 0.1524)
				(type default)
			)
			(layer "F.SilkS")
		)
		(fp_circle
			(center 0 0)
			(end 7.999984 0)
			(stroke
				(width 0.1524)
				(type default)
			)
			(fill no)
			(layer "B.SilkS")
		)
		(fp_circle
			(center 0 0)
			(end 7.999984 0)
			(stroke
				(width 0.1)
				(type default)
			)
			(fill no)
			(layer "B.Fab")
		)
		(fp_circle
			(center 0 0)
			(end 7.999984 0)
			(stroke
				(width 0.1)
				(type default)
			)
			(fill no)
			(layer "F.Fab")
		)
		(pad "" np_thru_hole circle
			(at 0 0)
			(size 4.5212 4.5212)
			(drill 4.5212)
			(layers "*.Cu" "*.Mask")
			(clearance 0.381)
			(thermal_gap 0.381)
		)
		(pad "2" thru_hole circle
			(at 3.6322 0)
			(size 0.762 0.762)
			(drill 0.5588)
			(layers "*.Cu" "*.Mask")
			(remove_unused_layers no)
			(net "GND")
			(clearance 0.1524)
			(thermal_gap 0.1524)
		)
		(pad "3" thru_hole circle
			(at 2.568448 -2.568448)
			(size 0.762 0.762)
			(drill 0.5588)
			(layers "*.Cu" "*.Mask")
			(remove_unused_layers no)
			(net "GND")
			(clearance 0.1524)
			(thermal_gap 0.1524)
		)
		(pad "4" thru_hole circle
			(at 0 -3.6322)
			(size 0.762 0.762)
			(drill 0.5588)
			(layers "*.Cu" "*.Mask")
			(remove_unused_layers no)
			(net "GND")
			(clearance 0.1524)
			(thermal_gap 0.1524)
		)
		(pad "5" thru_hole circle
			(at -2.568448 -2.568448)
			(size 0.762 0.762)
			(drill 0.5588)
			(layers "*.Cu" "*.Mask")
			(remove_unused_layers no)
			(net "GND")
			(clearance 0.1524)
			(thermal_gap 0.1524)
		)
		(pad "6" thru_hole circle
			(at -3.6322 0)
			(size 0.762 0.762)
			(drill 0.5588)
			(layers "*.Cu" "*.Mask")
			(remove_unused_layers no)
			(net "GND")
			(clearance 0.1524)
			(thermal_gap 0.1524)
		)
		(pad "7" thru_hole circle
			(at -2.568448 2.568448)
			(size 0.762 0.762)
			(drill 0.5588)
			(layers "*.Cu" "*.Mask")
			(remove_unused_layers no)
			(net "GND")
			(clearance 0.1524)
			(thermal_gap 0.1524)
		)
		(pad "8" thru_hole circle
			(at 0 3.6322)
			(size 0.762 0.762)
			(drill 0.5588)
			(layers "*.Cu" "*.Mask")
			(remove_unused_layers no)
			(net "GND")
			(clearance 0.1524)
			(thermal_gap 0.1524)
		)
		(pad "9" thru_hole circle
			(at 2.568448 2.568448)
			(size 0.762 0.762)
			(drill 0.5588)
			(layers "*.Cu" "*.Mask")
			(remove_unused_layers no)
			(net "GND")
			(clearance 0.1524)
			(thermal_gap 0.1524)
		)
		(zone
			(layer "F.Cu")
			(hatch none 0.5)
			(connect_pads
				(clearance 0)
			)
			(min_thickness 0.25)
			(keepout
				(tracks not_allowed)
				(vias allowed)
				(pads allowed)
				(copperpour not_allowed)
				(footprints allowed)
			)
			(placement
				(enabled no)
				(sheetname "")
			)
			(fill
				(thermal_gap 0.5)
				(thermal_bridge_width 0.5)
				(island_removal_mode 0)
			)
			(polygon
				(pts
					(arc
						(start 29.649674 -262.899906)
						(mid 21.64969 -270.89989)
						(end 29.649674 -278.899874)
					)
					(arc
						(start 29.649674 -275.64969)
						(mid 24.899874 -270.89989)
						(end 29.649674 -266.15009)
					)
				)
			)
		)
		(zone
			(layer "F.Cu")
			(hatch none 0.5)
			(connect_pads
				(clearance 0)
			)
			(min_thickness 0.25)
			(keepout
				(tracks not_allowed)
				(vias allowed)
				(pads allowed)
				(copperpour not_allowed)
				(footprints allowed)
			)
			(placement
				(enabled no)
				(sheetname "")
			)
			(fill
				(thermal_gap 0.5)
				(thermal_bridge_width 0.5)
				(island_removal_mode 0)
			)
			(polygon
				(pts
					(arc
						(start 29.649674 -262.899906)
						(mid 37.649658 -270.89989)
						(end 29.649674 -278.899874)
					)
					(arc
						(start 29.649674 -275.64969)
						(mid 34.399474 -270.89989)
						(end 29.649674 -266.15009)
					)
				)
			)
		)
		(zone
			(layers "F.Cu" "B.Cu" "In1.Cu" "In2.Cu" "In3.Cu" "In4.Cu" "In5.Cu" "In6.Cu"
				"In7.Cu" "In8.Cu" "In9.Cu" "In10.Cu" "In11.Cu" "In12.Cu" "In13.Cu" "In14.Cu"
				"In15.Cu" "In16.Cu"
			)
			(hatch none 0.5)
			(connect_pads
				(clearance 0)
			)
			(min_thickness 0.25)
			(keepout
				(tracks not_allowed)
				(vias allowed)
				(pads allowed)
				(copperpour not_allowed)
				(footprints allowed)
			)
			(placement
				(enabled no)
				(sheetname "")
			)
			(fill
				(thermal_gap 0.5)
				(thermal_bridge_width 0.5)
				(island_removal_mode 0)
			)
			(polygon
				(pts
					(arc
						(start 32.415734 -270.89989)
						(mid 26.883614 -270.89989)
						(end 32.415734 -270.89989)
					)
				)
			)
		)
		(zone
			(layer "B.Cu")
			(hatch none 0.5)
			(connect_pads
				(clearance 0)
			)
			(min_thickness 0.25)
			(keepout
				(tracks not_allowed)
				(vias allowed)
				(pads allowed)
				(copperpour not_allowed)
				(footprints allowed)
			)
			(placement
				(enabled no)
				(sheetname "")
			)
			(fill
				(thermal_gap 0.5)
				(thermal_bridge_width 0.5)
				(island_removal_mode 0)
			)
			(polygon
				(pts
					(arc
						(start 29.649674 -265.89609)
						(mid 24.645874 -270.89989)
						(end 29.649674 -275.90369)
					)
					(arc
						(start 29.649674 -275.42109)
						(mid 25.128474 -270.89989)
						(end 29.649674 -266.37869)
					)
				)
			)
		)
		(zone
			(layer "B.Cu")
			(hatch none 0.5)
			(connect_pads
				(clearance 0)
			)
			(min_thickness 0.25)
			(keepout
				(tracks not_allowed)
				(vias allowed)
				(pads allowed)
				(copperpour not_allowed)
				(footprints allowed)
			)
			(placement
				(enabled no)
				(sheetname "")
			)
			(fill
				(thermal_gap 0.5)
				(thermal_bridge_width 0.5)
				(island_removal_mode 0)
			)
			(polygon
				(pts
					(arc
						(start 29.649674 -265.89609)
						(mid 34.653474 -270.89989)
						(end 29.649674 -275.90369)
					)
					(arc
						(start 29.649674 -275.42109)
						(mid 34.170874 -270.89989)
						(end 29.649674 -266.37869)
					)
				)
			)
		)
	)
	(footprint ""
		(layer "F.Cu")
		(at 311.532016 -32.848042 90)
		(property "Reference" "PC957"
			(at 0 0 90)
			(layer "F.SilkS")
			(hide yes)
			(effects
				(font
					(size 1.27 1.27)
				)
			)
		)
		(property "Value" ""
			(at 0 0 90)
			(layer "F.Fab")
			(effects
				(font
					(size 1.27 1.27)
				)
			)
		)
		(duplicate_pad_numbers_are_jumpers no)
		(fp_line
			(start 0.7874 -0.4064)
			(end 0.7874 0.4064)
			(stroke
				(width 0.1524)
				(type default)
			)
			(layer "F.SilkS")
		)
		(fp_line
			(start -0.7874 -0.4064)
			(end 0.7874 -0.4064)
			(stroke
				(width 0.1524)
				(type default)
			)
			(layer "F.SilkS")
		)
		(fp_line
			(start 0.7874 0.4064)
			(end -0.7874 0.4064)
			(stroke
				(width 0.1524)
				(type default)
			)
			(layer "F.SilkS")
		)
		(fp_line
			(start -0.7874 0.4064)
			(end -0.7874 -0.4064)
			(stroke
				(width 0.1524)
				(type default)
			)
			(layer "F.SilkS")
		)
		(fp_line
			(start -0.12065 -0.305054)
			(end -0.12065 -0.2794)
			(stroke
				(width 0.1)
				(type default)
			)
			(layer "F.Fab")
		)
		(fp_line
			(start -0.67945 -0.305054)
			(end -0.12065 -0.305054)
			(stroke
				(width 0.1)
				(type default)
			)
			(layer "F.Fab")
		)
		(fp_line
			(start 0.67945 -0.3048)
			(end 0.67945 0.3048)
			(stroke
				(width 0.1)
				(type default)
			)
			(layer "F.Fab")
		)
		(fp_line
			(start 0.12065 -0.3048)
			(end 0.67945 -0.3048)
			(stroke
				(width 0.1)
				(type default)
			)
			(layer "F.Fab")
		)
		(fp_line
			(start 0.12065 -0.2794)
			(end 0.12065 -0.3048)
			(stroke
				(width 0.1)
				(type default)
			)
			(layer "F.Fab")
		)
		(fp_line
			(start -0.12065 -0.2794)
			(end 0.12065 -0.2794)
			(stroke
				(width 0.1)
				(type default)
			)
			(layer "F.Fab")
		)
		(fp_line
			(start 0.120396 0.2794)
			(end -0.12065 0.2794)
			(stroke
				(width 0.1)
				(type default)
			)
			(layer "F.Fab")
		)
		(fp_line
			(start -0.12065 0.2794)
			(end -0.12065 0.3048)
			(stroke
				(width 0.1)
				(type default)
			)
			(layer "F.Fab")
		)
		(fp_line
			(start 0.67945 0.3048)
			(end 0.120396 0.3048)
			(stroke
				(width 0.1)
				(type default)
			)
			(layer "F.Fab")
		)
		(fp_line
			(start 0.120396 0.3048)
			(end 0.120396 0.2794)
			(stroke
				(width 0.1)
				(type default)
			)
			(layer "F.Fab")
		)
		(fp_line
			(start -0.12065 0.3048)
			(end -0.67945 0.3048)
			(stroke
				(width 0.1)
				(type default)
			)
			(layer "F.Fab")
		)
		(fp_line
			(start -0.67945 0.3048)
			(end -0.67945 -0.305054)
			(stroke
				(width 0.1)
				(type default)
			)
			(layer "F.Fab")
		)
		(pad "1" smd circle
			(at -0.40005 0 90)
			(size 0 0)
			(layers "F.Cu" "F.Mask" "F.Paste")
			(net "P3V3_SSD11_CO_DV_DT")
		)
		(pad "2" smd circle
			(at 0.40005 0 90)
			(size 0 0)
			(layers "F.Cu" "F.Mask" "F.Paste")
			(net "GND")
		)
	)
	(footprint ""
		(layer "F.Cu")
		(at 16.702786 -112.139476 -90)
		(property "Reference" "PC664"
			(at 0 0 270)
			(layer "F.SilkS")
			(hide yes)
			(effects
				(font
					(size 1.27 1.27)
				)
			)
		)
		(property "Value" ""
			(at 0 0 270)
			(layer "F.Fab")
			(effects
				(font
					(size 1.27 1.27)
				)
			)
		)
		(duplicate_pad_numbers_are_jumpers no)
		(fp_line
			(start -0.7874 0.4064)
			(end -0.7874 -0.4064)
			(stroke
				(width 0.1524)
				(type default)
			)
			(layer "F.SilkS")
		)
		(fp_line
			(start 0.7874 0.4064)
			(end -0.7874 0.4064)
			(stroke
				(width 0.1524)
				(type default)
			)
			(layer "F.SilkS")
		)
		(fp_line
			(start -0.7874 -0.4064)
			(end 0.7874 -0.4064)
			(stroke
				(width 0.1524)
				(type default)
			)
			(layer "F.SilkS")
		)
		(fp_line
			(start 0.7874 -0.4064)
			(end 0.7874 0.4064)
			(stroke
				(width 0.1524)
				(type default)
			)
			(layer "F.SilkS")
		)
		(fp_line
			(start -0.67945 0.3048)
			(end -0.67945 -0.305054)
			(stroke
				(width 0.1)
				(type default)
			)
			(layer "F.Fab")
		)
		(fp_line
			(start -0.12065 0.3048)
			(end -0.67945 0.3048)
			(stroke
				(width 0.1)
				(type default)
			)
			(layer "F.Fab")
		)
		(fp_line
			(start 0.120396 0.3048)
			(end 0.120396 0.2794)
			(stroke
				(width 0.1)
				(type default)
			)
			(layer "F.Fab")
		)
		(fp_line
			(start 0.67945 0.3048)
			(end 0.120396 0.3048)
			(stroke
				(width 0.1)
				(type default)
			)
			(layer "F.Fab")
		)
		(fp_line
			(start -0.12065 0.2794)
			(end -0.12065 0.3048)
			(stroke
				(width 0.1)
				(type default)
			)
			(layer "F.Fab")
		)
		(fp_line
			(start 0.120396 0.2794)
			(end -0.12065 0.2794)
			(stroke
				(width 0.1)
				(type default)
			)
			(layer "F.Fab")
		)
		(fp_line
			(start -0.12065 -0.2794)
			(end 0.12065 -0.2794)
			(stroke
				(width 0.1)
				(type default)
			)
			(layer "F.Fab")
		)
		(fp_line
			(start 0.12065 -0.2794)
			(end 0.12065 -0.3048)
			(stroke
				(width 0.1)
				(type default)
			)
			(layer "F.Fab")
		)
		(fp_line
			(start 0.12065 -0.3048)
			(end 0.67945 -0.3048)
			(stroke
				(width 0.1)
				(type default)
			)
			(layer "F.Fab")
		)
		(fp_line
			(start 0.67945 -0.3048)
			(end 0.67945 0.3048)
			(stroke
				(width 0.1)
				(type default)
			)
			(layer "F.Fab")
		)
		(fp_line
			(start -0.67945 -0.305054)
			(end -0.12065 -0.305054)
			(stroke
				(width 0.1)
				(type default)
			)
			(layer "F.Fab")
		)
		(fp_line
			(start -0.12065 -0.305054)
			(end -0.12065 -0.2794)
			(stroke
				(width 0.1)
				(type default)
			)
			(layer "F.Fab")
		)
		(pad "1" smd circle
			(at -0.40005 0 270)
			(size 0 0)
			(layers "F.Cu" "F.Mask" "F.Paste")
			(net "P3V3_NIC0_CO_MODE")
		)
		(pad "2" smd circle
			(at 0.40005 0 270)
			(size 0 0)
			(layers "F.Cu" "F.Mask" "F.Paste")
			(net "GND")
		)
	)
	(footprint ""
		(layer "F.Cu")
		(at 327.008998 -95.041466 -90)
		(property "Reference" "PC327"
			(at 0 0 270)
			(layer "F.SilkS")
			(hide yes)
			(effects
				(font
					(size 1.27 1.27)
				)
			)
		)
		(property "Value" ""
			(at 0 0 270)
			(layer "F.Fab")
			(effects
				(font
					(size 1.27 1.27)
				)
			)
		)
		(duplicate_pad_numbers_are_jumpers no)
		(fp_line
			(start -0.7874 0.4064)
			(end -0.7874 -0.4064)
			(stroke
				(width 0.1524)
				(type default)
			)
			(layer "F.SilkS")
		)
		(fp_line
			(start 0.7874 0.4064)
			(end -0.7874 0.4064)
			(stroke
				(width 0.1524)
				(type default)
			)
			(layer "F.SilkS")
		)
		(fp_line
			(start -0.7874 -0.4064)
			(end 0.7874 -0.4064)
			(stroke
				(width 0.1524)
				(type default)
			)
			(layer "F.SilkS")
		)
		(fp_line
			(start 0.7874 -0.4064)
			(end 0.7874 0.4064)
			(stroke
				(width 0.1524)
				(type default)
			)
			(layer "F.SilkS")
		)
		(fp_line
			(start -0.67945 0.3048)
			(end -0.67945 -0.305054)
			(stroke
				(width 0.1)
				(type default)
			)
			(layer "F.Fab")
		)
		(fp_line
			(start -0.12065 0.3048)
			(end -0.67945 0.3048)
			(stroke
				(width 0.1)
				(type default)
			)
			(layer "F.Fab")
		)
		(fp_line
			(start 0.120396 0.3048)
			(end 0.120396 0.2794)
			(stroke
				(width 0.1)
				(type default)
			)
			(layer "F.Fab")
		)
		(fp_line
			(start 0.67945 0.3048)
			(end 0.120396 0.3048)
			(stroke
				(width 0.1)
				(type default)
			)
			(layer "F.Fab")
		)
		(fp_line
			(start -0.12065 0.2794)
			(end -0.12065 0.3048)
			(stroke
				(width 0.1)
				(type default)
			)
			(layer "F.Fab")
		)
		(fp_line
			(start 0.120396 0.2794)
			(end -0.12065 0.2794)
			(stroke
				(width 0.1)
				(type default)
			)
			(layer "F.Fab")
		)
		(fp_line
			(start -0.12065 -0.2794)
			(end 0.12065 -0.2794)
			(stroke
				(width 0.1)
				(type default)
			)
			(layer "F.Fab")
		)
		(fp_line
			(start 0.12065 -0.2794)
			(end 0.12065 -0.3048)
			(stroke
				(width 0.1)
				(type default)
			)
			(layer "F.Fab")
		)
		(fp_line
			(start 0.12065 -0.3048)
			(end 0.67945 -0.3048)
			(stroke
				(width 0.1)
				(type default)
			)
			(layer "F.Fab")
		)
		(fp_line
			(start 0.67945 -0.3048)
			(end 0.67945 0.3048)
			(stroke
				(width 0.1)
				(type default)
			)
			(layer "F.Fab")
		)
		(fp_line
			(start -0.67945 -0.305054)
			(end -0.12065 -0.305054)
			(stroke
				(width 0.1)
				(type default)
			)
			(layer "F.Fab")
		)
		(fp_line
			(start -0.12065 -0.305054)
			(end -0.12065 -0.2794)
			(stroke
				(width 0.1)
				(type default)
			)
			(layer "F.Fab")
		)
		(pad "1" smd circle
			(at -0.40005 0 270)
			(size 0 0)
			(layers "F.Cu" "F.Mask" "F.Paste")
			(net "P12V_NIC5_SS")
		)
		(pad "2" smd circle
			(at 0.40005 0 270)
			(size 0 0)
			(layers "F.Cu" "F.Mask" "F.Paste")
			(net "GND")
		)
	)
	(footprint ""
		(layer "F.Cu")
		(at 337.488022 -319.420494 90)
		(property "Reference" "R5791"
			(at 0 0 90)
			(layer "F.SilkS")
			(hide yes)
			(effects
				(font
					(size 1.27 1.27)
				)
			)
		)
		(property "Value" ""
			(at 0 0 90)
			(layer "F.Fab")
			(effects
				(font
					(size 1.27 1.27)
				)
			)
		)
		(duplicate_pad_numbers_are_jumpers no)
		(fp_line
			(start 2.576322 -1.1303)
			(end 2.576322 1.1303)
			(stroke
				(width 0.1524)
				(type default)
			)
			(layer "F.SilkS")
		)
		(fp_line
			(start -2.576322 -1.1303)
			(end 2.576322 -1.1303)
			(stroke
				(width 0.1524)
				(type default)
			)
			(layer "F.SilkS")
		)
		(fp_line
			(start 2.576322 1.1303)
			(end -2.576322 1.1303)
			(stroke
				(width 0.1524)
				(type default)
			)
			(layer "F.SilkS")
		)
		(fp_line
			(start -2.576322 1.1303)
			(end -2.576322 -1.1303)
			(stroke
				(width 0.1524)
				(type default)
			)
			(layer "F.SilkS")
		)
		(fp_line
			(start 1.649984 -0.899922)
			(end -1.649984 -0.899922)
			(stroke
				(width 0.1)
				(type default)
			)
			(layer "F.Fab")
		)
		(fp_line
			(start -1.649984 -0.899922)
			(end -1.649984 0.899922)
			(stroke
				(width 0.1)
				(type default)
			)
			(layer "F.Fab")
		)
		(fp_line
			(start 1.649984 0.899922)
			(end 1.649984 -0.899922)
			(stroke
				(width 0.1)
				(type default)
			)
			(layer "F.Fab")
		)
		(fp_line
			(start -1.649984 0.899922)
			(end 1.649984 0.899922)
			(stroke
				(width 0.1)
				(type default)
			)
			(layer "F.Fab")
		)
		(pad "1A" smd rect
			(at -1.700022 0 90)
			(size 1.4986 2.0066)
			(layers "F.Cu" "F.Mask" "F.Paste")
			(net "P0V8_PEX2")
		)
		(pad "1B" smd rect
			(at -1.077722 0 90)
			(size 0.254 0.508)
			(layers "F.Cu" "F.Mask" "F.Paste")
			(net "P0V8_PEX2")
		)
		(pad "2A" smd rect
			(at 1.700022 0 90)
			(size 1.4986 2.0066)
			(layers "F.Cu" "F.Mask" "F.Paste")
			(net "P0V8_SERDES_VDDA_PEX2")
		)
		(pad "2B" smd rect
			(at 1.077722 0 90)
			(size 0.254 0.508)
			(layers "F.Cu" "F.Mask" "F.Paste")
			(net "P0V8_SERDES_VDDA_PEX2")
		)
	)
)
